# BASEBOARD_FAB2 (Tioga Pass) — schematic netlist excerpt (pin names and nets, part order shuffled) for the footprints in the layout excerpt that follows; sources: Cadence DE-HDL packaged netlist, KiCad conversion of Wiwynn_Tioga_Pass_MB.brd

C7C8  SC22U16V5MX-4-GP  20%  pkg SMD-BCG5  page 212 : \1\ = VR_FET_SW_P12V_STBY_PVCCIO_CPU0 ; \2\ = GND
FB2T4  HCB1608KF-800T30-GP  pkg DISCRET-G9  page 149 : \1\ = P3V3_STBY ; \2\ = VCC_D_3V3
U8G2  TTL1G07_A  74LVC1G07 IC  pkg SOP  page 161 : A = FAN_PWM_OUT_SYS0 ; Y = FAN_PWM_OUT_SYS0_BUF

(kicad_pcb
	(version 20260206)
	(generator "pcbnew")
	(generator_version "10.0")
	(general
		(thickness 1.6)
		(legacy_teardrops no)
	)
	(paper "A4")
	(title_block
		(title "Wiwynn_Tioga_Pass_MB.brd")
		(comment 1 "Tioga Pass / footprints 4034-4036 of 4770")
	)
	(layers
		(0 "F.Cu" signal "TOP")
		(4 "In1.Cu" signal "L2GND")
		(6 "In2.Cu" signal "L3")
		(8 "In3.Cu" signal "L4GND")
		(10 "In4.Cu" signal "L5")
		(12 "In5.Cu" signal "L6GND")
		(14 "In6.Cu" signal "L7VCC")
		(16 "In7.Cu" signal "L8VCC")
		(18 "In8.Cu" signal "L9GND")
		(20 "In9.Cu" signal "L10")
		(22 "In10.Cu" signal "L11GND")
		(24 "In11.Cu" signal "L12")
		(26 "In12.Cu" signal "L13GND")
		(2 "B.Cu" signal "BOTTOM")
		(9 "F.Adhes" user "F.Adhesive")
		(11 "B.Adhes" user "B.Adhesive")
		(13 "F.Paste" user "Package Geometry/Pastemask Top")
		(15 "B.Paste" user "Package Geometry/Pastemask Bottom")
		(5 "F.SilkS" user "Ref Des/Silkscreen Top")
		(7 "B.SilkS" user "Ref Des/Silkscreen Bottom")
		(1 "F.Mask" user "Board Geometry/Soldermask Top")
		(3 "B.Mask" user "Board Geometry/Soldermask Bottom")
		(17 "Dwgs.User" user "User.Drawings")
		(19 "Cmts.User" user "User.Comments")
		(21 "Eco1.User" user "User.Eco1")
		(23 "Eco2.User" user "User.Eco2")
		(25 "Edge.Cuts" user "Board Geometry/Outline")
		(27 "Margin" user)
		(31 "F.CrtYd" user "Package Geometry/Place Bound Top")
		(29 "B.CrtYd" user "Package Geometry/Place Bound Bottom")
		(35 "F.Fab" user "Ref Des/Assembly Top")
		(33 "B.Fab" user "Ref Des/Assembly Bottom")
	)
	(footprint ""
		(layer "B.Cu")
		(at 411.48 0.2794)
		(property "Reference" "U8G2"
			(at -5.334 1.24333 180)
			(unlocked yes)
			(layer "B.SilkS")
			(effects
				(font
					(size 0.7874 0.5842)
					(thickness 0.1524)
				)
				(justify left mirror)
			)
		)
		(property "Value" ""
			(at 0 0 0)
			(layer "B.Fab")
			(effects
				(font
					(size 1.27 1.27)
				)
				(justify mirror)
			)
		)
		(duplicate_pad_numbers_are_jumpers no)
		(fp_circle
			(center 1.03124 -0.04826)
			(end 1.15824 -0.04826)
			(stroke
				(width 0.254)
				(type default)
			)
			(fill no)
			(layer "B.SilkS")
		)
		(fp_poly
			(pts
				(xy -0.21463 -0.450088) (xy -1.56337 -0.450088) (xy -1.56337 1.75006) (xy -0.21463 1.75006)
			)
			(stroke
				(width 0)
				(type default)
			)
			(fill no)
			(layer "B.CrtYd")
		)
		(fp_line
			(start -1.56337 -0.450088)
			(end -1.56337 1.75006)
			(stroke
				(width 0.1)
				(type default)
			)
			(layer "B.Fab")
		)
		(fp_line
			(start -1.56337 1.75006)
			(end -0.21463 1.75006)
			(stroke
				(width 0.1)
				(type default)
			)
			(layer "B.Fab")
		)
		(fp_line
			(start -0.21463 -0.450088)
			(end -1.56337 -0.450088)
			(stroke
				(width 0.1)
				(type default)
			)
			(layer "B.Fab")
		)
		(fp_line
			(start -0.21463 1.75006)
			(end -0.21463 -0.450088)
			(stroke
				(width 0.1)
				(type default)
			)
			(layer "B.Fab")
		)
		(fp_circle
			(center 0.4699 -0.8382)
			(end 0.5969 -0.8382)
			(stroke
				(width 0.254)
				(type default)
			)
			(fill no)
			(layer "B.Fab")
		)
		(pad "1" smd rect
			(at 0 0 180)
			(size 1.016 0.381)
			(layers "B.Cu" "B.Mask" "B.Paste")
			(net "Net_6469")
		)
		(pad "2" smd rect
			(at 0 0.649986 180)
			(size 1.016 0.381)
			(layers "B.Cu" "B.Mask" "B.Paste")
			(net "FAN_PWM_OUT_SYS0")
		)
		(pad "3" smd rect
			(at 0 1.299972 180)
			(size 1.016 0.381)
			(layers "B.Cu" "B.Mask" "B.Paste")
			(net "GND")
		)
		(pad "4" smd rect
			(at -1.778 1.299972 180)
			(size 1.016 0.381)
			(layers "B.Cu" "B.Mask" "B.Paste")
			(net "FAN_PWM_OUT_SYS0_BUF")
		)
		(pad "5" smd rect
			(at -1.778 0 180)
			(size 1.016 0.381)
			(layers "B.Cu" "B.Mask" "B.Paste")
			(net "P3V3_STBY")
		)
	)
	(footprint ""
		(layer "B.Cu")
		(at 413.270446 -39.735252 -90)
		(property "Reference" "FB2T4"
			(at 0 0 90)
			(layer "B.SilkS")
			(hide yes)
			(effects
				(font
					(size 1.27 1.27)
				)
				(justify mirror)
			)
		)
		(property "Value" "*"
			(at -0.0254 -2.8829 270)
			(unlocked yes)
			(layer "B.Fab")
			(hide yes)
			(effects
				(font
					(size 1.27 1.016)
					(thickness 0.1524)
				)
				(justify mirror)
			)
		)
		(property "Device Type" "HCB1608KF-800T30-GP_DISCRET-G9A"
			(at -0.0254 -4.4069 270)
			(unlocked yes)
			(layer "B.Fab")
			(hide yes)
			(effects
				(font
					(size 1.27 1.016)
					(thickness 0.1524)
				)
				(justify mirror)
			)
		)
		(duplicate_pad_numbers_are_jumpers no)
		(fp_line
			(start -0.254 0)
			(end 0.254 0)
			(stroke
				(width 0.2032)
				(type default)
			)
			(layer "B.SilkS")
		)
		(fp_rect
			(start 0.5842 1.3335)
			(end -0.5842 -1.3335)
			(stroke
				(width 0)
				(type default)
			)
			(fill no)
			(layer "B.CrtYd")
		)
		(fp_rect
			(start 0.5842 1.3335)
			(end -0.5842 -1.3335)
			(stroke
				(width 0)
				(type default)
			)
			(fill no)
			(layer "B.Fab")
		)
		(pad "1" smd custom
			(at 0 -0.762 90)
			(size 0.2159 0.2159)
			(layers "B.Cu" "B.Mask" "B.Paste")
			(net "P3V3_STBY")
			(options
				(clearance outline)
				(anchor circle)
			)
			(primitives
				(gr_poly
					(pts
						(arc
							(start -0.3302 0.4318)
							(mid -0.402042 0.402042)
							(end -0.4318 0.3302)
						)
						(arc
							(start -0.4318 -0.3302)
							(mid -0.402042 -0.402042)
							(end -0.3302 -0.4318)
						)
						(arc
							(start 0.3302 -0.4318)
							(mid 0.402042 -0.402042)
							(end 0.4318 -0.3302)
						)
						(arc
							(start 0.4318 0.3302)
							(mid 0.402042 0.402042)
							(end 0.3302 0.4318)
						)
					)
					(width 0)
					(fill yes)
				)
			)
		)
		(pad "2" smd custom
			(at 0 0.762 90)
			(size 0.2159 0.2159)
			(layers "B.Cu" "B.Mask" "B.Paste")
			(net "VCC_D_3V3")
			(options
				(clearance outline)
				(anchor circle)
			)
			(primitives
				(gr_poly
					(pts
						(arc
							(start -0.3302 0.4318)
							(mid -0.402042 0.402042)
							(end -0.4318 0.3302)
						)
						(arc
							(start -0.4318 -0.3302)
							(mid -0.402042 -0.402042)
							(end -0.3302 -0.4318)
						)
						(arc
							(start 0.3302 -0.4318)
							(mid 0.402042 -0.402042)
							(end 0.4318 -0.3302)
						)
						(arc
							(start 0.4318 0.3302)
							(mid 0.402042 0.402042)
							(end 0.3302 0.4318)
						)
					)
					(width 0)
					(fill yes)
				)
			)
		)
	)
	(footprint ""
		(layer "B.Cu")
		(at 356.08768 -96.062292 90)
		(property "Reference" "C7C8"
			(at 0 0 90)
			(layer "B.SilkS")
			(hide yes)
			(effects
				(font
					(size 1.27 1.27)
				)
				(justify mirror)
			)
		)
		(property "Value" "*"
			(at 0.0762 -6.2357 90)
			(unlocked yes)
			(layer "B.Fab")
			(hide yes)
			(effects
				(font
					(size 1.27 1.016)
					(thickness 0.1524)
				)
				(justify mirror)
			)
		)
		(property "Device Type" "SC22U16V5MX-4-GP_SMD-BCG5-SC22A"
			(at 0.0762 -8.2677 90)
			(unlocked yes)
			(layer "B.Fab")
			(hide yes)
			(effects
				(font
					(size 1.27 1.016)
					(thickness 0.1524)
				)
				(justify mirror)
			)
		)
		(duplicate_pad_numbers_are_jumpers no)
		(fp_line
			(start -0.635 0)
			(end 0.635 0)
			(stroke
				(width 0.508)
				(type default)
			)
			(layer "B.SilkS")
		)
		(fp_rect
			(start 0.9652 1.778)
			(end -0.9652 -1.778)
			(stroke
				(width 0)
				(type default)
			)
			(fill no)
			(layer "B.CrtYd")
		)
		(fp_poly
			(pts
				(xy 0.9652 -1.778) (xy -0.9652 -1.778) (xy -0.9652 1.778) (xy 0.9652 1.778)
			)
			(stroke
				(width 0)
				(type default)
			)
			(fill no)
			(layer "B.Fab")
		)
		(pad "1" smd rect
			(at 0 -0.9652 270)
			(size 1.397 1.143)
			(layers "B.Cu" "B.Mask" "B.Paste")
			(net "VR_FET_SW_P12V_STBY_PVCCIO_CPU0")
		)
		(pad "2" smd rect
			(at 0 0.9652 270)
			(size 1.397 1.143)
			(layers "B.Cu" "B.Mask" "B.Paste")
			(net "GND")
		)
	)
)
